# T6G (Grand Teton) — schematic netlist excerpt (pin names and nets, part order shuffled) for the footprints in the layout excerpt that follows; sources: Cadence DE-HDL packaged netlist, KiCad conversion of 04192023_DAF0TMB3IC0_F0TG_MB_C_brd_V02_OCP.brd

PC388  Q_CAPP  220UF 4V 20% SPCAP  pkg SMLF  page 218 : A = PVDDCR_CPU1_P1 ; B = GND
C2233  Q_CAP  22UF 4V 20% X6S  pkg C0402  page 69 : A = PVDDCR_CPU1_P0 ; B = GND

(kicad_pcb
	(version 20260206)
	(generator "pcbnew")
	(generator_version "10.0")
	(general
		(thickness 1.6)
		(legacy_teardrops no)
	)
	(paper "A4")
	(title_block
		(title "04192023_DAF0TMB3IC0_F0TG_MB_C_brd_V02_OCP.brd")
		(comment 1 "Grand Teton / footprints 5905-5906 of 8354")
	)
	(layers
		(0 "F.Cu" signal "TOP")
		(4 "In1.Cu" signal "GND")
		(6 "In2.Cu" signal "IN1")
		(8 "In3.Cu" signal "GND1")
		(10 "In4.Cu" signal "IN2")
		(12 "In5.Cu" signal "GND2")
		(14 "In6.Cu" signal "IN3")
		(16 "In7.Cu" signal "GND3")
		(18 "In8.Cu" signal "VCC")
		(20 "In9.Cu" signal "VCC1")
		(22 "In10.Cu" signal "GND4")
		(24 "In11.Cu" signal "IN4")
		(26 "In12.Cu" signal "GND5")
		(28 "In13.Cu" signal "IN5")
		(30 "In14.Cu" signal "GND6")
		(32 "In15.Cu" signal "IN6")
		(34 "In16.Cu" signal "GND7")
		(2 "B.Cu" signal "BOTTOM")
		(9 "F.Adhes" user "F.Adhesive")
		(11 "B.Adhes" user "B.Adhesive")
		(13 "F.Paste" user "Package Geometry/Pastemask Top")
		(15 "B.Paste" user "Package Geometry/Pastemask Bottom")
		(5 "F.SilkS" user "Ref Des/Silkscreen Top")
		(7 "B.SilkS" user "Ref Des/Silkscreen Bottom")
		(1 "F.Mask" user "Board Geometry/Soldermask Top")
		(3 "B.Mask" user "Board Geometry/Soldermask Bottom")
		(17 "Dwgs.User" user "User.Drawings")
		(19 "Cmts.User" user "User.Comments")
		(21 "Eco1.User" user "User.Eco1")
		(23 "Eco2.User" user "User.Eco2")
		(25 "Edge.Cuts" user "Board Geometry/Outline")
		(27 "Margin" user)
		(31 "F.CrtYd" user "Package Geometry/Place Bound Top")
		(29 "B.CrtYd" user "Package Geometry/Place Bound Bottom")
		(35 "F.Fab" user "Ref Des/Assembly Top")
		(33 "B.Fab" user "Ref Des/Assembly Bottom")
	)
	(footprint ""
		(layer "B.Cu")
		(at 348.101158 -271.878552 90)
		(property "Reference" "C2233"
			(at 0 0 90)
			(layer "B.SilkS")
			(hide yes)
			(effects
				(font
					(size 1.27 1.27)
				)
				(justify mirror)
			)
		)
		(property "Value" ""
			(at 0 0 90)
			(layer "B.Fab")
			(effects
				(font
					(size 1.27 1.27)
				)
				(justify mirror)
			)
		)
		(duplicate_pad_numbers_are_jumpers no)
		(fp_line
			(start 0.7874 -0.4064)
			(end -0.7874 -0.4064)
			(stroke
				(width 0.1524)
				(type default)
			)
			(layer "B.SilkS")
		)
		(fp_line
			(start -0.7874 -0.4064)
			(end -0.7874 0.4064)
			(stroke
				(width 0.1524)
				(type default)
			)
			(layer "B.SilkS")
		)
		(fp_line
			(start 0.7874 0.4064)
			(end 0.7874 -0.4064)
			(stroke
				(width 0.1524)
				(type default)
			)
			(layer "B.SilkS")
		)
		(fp_line
			(start -0.7874 0.4064)
			(end 0.7874 0.4064)
			(stroke
				(width 0.1524)
				(type default)
			)
			(layer "B.SilkS")
		)
		(fp_line
			(start 0.67945 -0.305054)
			(end 0.12065 -0.305054)
			(stroke
				(width 0.1)
				(type default)
			)
			(layer "B.Fab")
		)
		(fp_line
			(start 0.12065 -0.305054)
			(end 0.12065 -0.2794)
			(stroke
				(width 0.1)
				(type default)
			)
			(layer "B.Fab")
		)
		(fp_line
			(start -0.12065 -0.3048)
			(end -0.67945 -0.3048)
			(stroke
				(width 0.1)
				(type default)
			)
			(layer "B.Fab")
		)
		(fp_line
			(start -0.67945 -0.3048)
			(end -0.67945 0.3048)
			(stroke
				(width 0.1)
				(type default)
			)
			(layer "B.Fab")
		)
		(fp_line
			(start 0.12065 -0.2794)
			(end -0.12065 -0.2794)
			(stroke
				(width 0.1)
				(type default)
			)
			(layer "B.Fab")
		)
		(fp_line
			(start -0.12065 -0.2794)
			(end -0.12065 -0.3048)
			(stroke
				(width 0.1)
				(type default)
			)
			(layer "B.Fab")
		)
		(fp_line
			(start 0.12065 0.2794)
			(end 0.12065 0.3048)
			(stroke
				(width 0.1)
				(type default)
			)
			(layer "B.Fab")
		)
		(fp_line
			(start -0.120396 0.2794)
			(end 0.12065 0.2794)
			(stroke
				(width 0.1)
				(type default)
			)
			(layer "B.Fab")
		)
		(fp_line
			(start 0.67945 0.3048)
			(end 0.67945 -0.305054)
			(stroke
				(width 0.1)
				(type default)
			)
			(layer "B.Fab")
		)
		(fp_line
			(start 0.12065 0.3048)
			(end 0.67945 0.3048)
			(stroke
				(width 0.1)
				(type default)
			)
			(layer "B.Fab")
		)
		(fp_line
			(start -0.120396 0.3048)
			(end -0.120396 0.2794)
			(stroke
				(width 0.1)
				(type default)
			)
			(layer "B.Fab")
		)
		(fp_line
			(start -0.67945 0.3048)
			(end -0.120396 0.3048)
			(stroke
				(width 0.1)
				(type default)
			)
			(layer "B.Fab")
		)
		(pad "1" smd circle
			(at 0.40005 0 270)
			(size 0 0)
			(layers "B.Cu" "B.Mask" "B.Paste")
			(net "PVDDCR_CPU1_P0")
		)
		(pad "2" smd circle
			(at -0.40005 0 270)
			(size 0 0)
			(layers "B.Cu" "B.Mask" "B.Paste")
			(net "GND")
		)
	)
	(footprint ""
		(layer "B.Cu")
		(at 77.973682 -328.24547 -90)
		(property "Reference" "PC388"
			(at 9.98347 -1.374648 270)
			(unlocked yes)
			(layer "B.SilkS")
			(effects
				(font
					(size 0.7874 0.5842)
					(thickness 0.1524)
				)
				(justify left mirror)
			)
		)
		(property "Value" ""
			(at 0 0 90)
			(layer "B.Fab")
			(effects
				(font
					(size 1.27 1.27)
				)
				(justify mirror)
			)
		)
		(duplicate_pad_numbers_are_jumpers no)
		(fp_line
			(start -4.533392 2.249932)
			(end 4.533392 2.249932)
			(stroke
				(width 0.1524)
				(type default)
			)
			(layer "B.SilkS")
		)
		(fp_line
			(start 4.533392 2.249932)
			(end 4.533392 -2.249932)
			(stroke
				(width 0.1524)
				(type default)
			)
			(layer "B.SilkS")
		)
		(fp_line
			(start -4.533392 -2.249932)
			(end -4.533392 2.249932)
			(stroke
				(width 0.1524)
				(type default)
			)
			(layer "B.SilkS")
		)
		(fp_line
			(start 4.533392 -2.249932)
			(end -4.533392 -2.249932)
			(stroke
				(width 0.1524)
				(type default)
			)
			(layer "B.SilkS")
		)
		(fp_rect
			(start 5.39242 2.326132)
			(end 4.533392 -2.326132)
			(stroke
				(width 0)
				(type default)
			)
			(fill yes)
			(layer "B.SilkS")
		)
		(fp_line
			(start -3.750056 2.249932)
			(end 3.750056 2.249932)
			(stroke
				(width 0.1)
				(type default)
			)
			(layer "B.Fab")
		)
		(fp_line
			(start 3.750056 2.249932)
			(end 3.750056 -2.249932)
			(stroke
				(width 0.1)
				(type default)
			)
			(layer "B.Fab")
		)
		(fp_line
			(start -3.750056 -2.249932)
			(end -3.750056 2.249932)
			(stroke
				(width 0.1)
				(type default)
			)
			(layer "B.Fab")
		)
		(fp_line
			(start 3.750056 -2.249932)
			(end -3.750056 -2.249932)
			(stroke
				(width 0.1)
				(type default)
			)
			(layer "B.Fab")
		)
		(fp_text user "-"
			(at -4.712462 1.477264 270)
			(unlocked yes)
			(layer "B.SilkS")
			(effects
				(font
					(size 1.905 1.4224)
					(thickness 0.1524)
				)
				(justify left mirror)
			)
		)
		(fp_text user "+"
			(at 6.265418 0.05207 180)
			(unlocked yes)
			(layer "B.SilkS")
			(effects
				(font
					(size 1.905 1.4224)
					(thickness 0.1524)
				)
				(justify left mirror)
			)
		)
		(fp_text user "+"
			(at 6.322314 0.786384 180)
			(unlocked yes)
			(layer "B.Fab")
			(effects
				(font
					(size 1.905 1.4224)
					(thickness 0.1524)
				)
				(justify left mirror)
			)
		)
		(fp_text user "-"
			(at -4.8514 -0.14605 270)
			(unlocked yes)
			(layer "B.Fab")
			(effects
				(font
					(size 1.905 1.4224)
					(thickness 0.1524)
				)
				(justify left mirror)
			)
		)
		(pad "1" smd rect
			(at 3.199892 0 90)
			(size 2.413 2.8194)
			(layers "B.Cu" "B.Mask" "B.Paste")
			(net "PVDDCR_CPU1_P1")
		)
		(pad "2" smd rect
			(at -3.199892 0 90)
			(size 2.413 2.8194)
			(layers "B.Cu" "B.Mask" "B.Paste")
			(net "GND")
		)
	)
)
